# T6G (Grand Teton) — schematic netlist excerpt (pin names and nets, part order shuffled) for the footprints in the layout excerpt that follows; sources: Cadence DE-HDL packaged netlist, KiCad conversion of 04192023_DAF0TMB3IC0_F0TG_MB_C_brd_V02_OCP.brd

PC6506  Q_CAP  1UF 25V 10% X6S  pkg C0402  page 360 : A = P1V8_RETIMER_CPU0_VCC ; B = GND
PC131  Q_CAP  2.2UF 10V 10% X6S  pkg C0402  page 203 : A = PVDDCR_CPU1_P0_VCC5 ; B = GND

(kicad_pcb
	(version 20260206)
	(generator "pcbnew")
	(generator_version "10.0")
	(general
		(thickness 1.6)
		(legacy_teardrops no)
	)
	(paper "A4")
	(title_block
		(title "04192023_DAF0TMB3IC0_F0TG_MB_C_brd_V02_OCP.brd")
		(comment 1 "Grand Teton / footprints 2968-2969 of 8354")
	)
	(layers
		(0 "F.Cu" signal "TOP")
		(4 "In1.Cu" signal "GND")
		(6 "In2.Cu" signal "IN1")
		(8 "In3.Cu" signal "GND1")
		(10 "In4.Cu" signal "IN2")
		(12 "In5.Cu" signal "GND2")
		(14 "In6.Cu" signal "IN3")
		(16 "In7.Cu" signal "GND3")
		(18 "In8.Cu" signal "VCC")
		(20 "In9.Cu" signal "VCC1")
		(22 "In10.Cu" signal "GND4")
		(24 "In11.Cu" signal "IN4")
		(26 "In12.Cu" signal "GND5")
		(28 "In13.Cu" signal "IN5")
		(30 "In14.Cu" signal "GND6")
		(32 "In15.Cu" signal "IN6")
		(34 "In16.Cu" signal "GND7")
		(2 "B.Cu" signal "BOTTOM")
		(9 "F.Adhes" user "F.Adhesive")
		(11 "B.Adhes" user "B.Adhesive")
		(13 "F.Paste" user "Package Geometry/Pastemask Top")
		(15 "B.Paste" user "Package Geometry/Pastemask Bottom")
		(5 "F.SilkS" user "Ref Des/Silkscreen Top")
		(7 "B.SilkS" user "Ref Des/Silkscreen Bottom")
		(1 "F.Mask" user "Board Geometry/Soldermask Top")
		(3 "B.Mask" user "Board Geometry/Soldermask Bottom")
		(17 "Dwgs.User" user "User.Drawings")
		(19 "Cmts.User" user "User.Comments")
		(21 "Eco1.User" user "User.Eco1")
		(23 "Eco2.User" user "User.Eco2")
		(25 "Edge.Cuts" user "Board Geometry/Outline")
		(27 "Margin" user)
		(31 "F.CrtYd" user "Package Geometry/Place Bound Top")
		(29 "B.CrtYd" user "Package Geometry/Place Bound Bottom")
		(35 "F.Fab" user "Ref Des/Assembly Top")
		(33 "B.Fab" user "Ref Des/Assembly Bottom")
	)
	(footprint ""
		(layer "F.Cu")
		(at 246.245888 -293.13505 -90)
		(property "Reference" "PC6506"
			(at 0 0 270)
			(layer "F.SilkS")
			(hide yes)
			(effects
				(font
					(size 1.27 1.27)
				)
			)
		)
		(property "Value" ""
			(at 0 0 270)
			(layer "F.Fab")
			(effects
				(font
					(size 1.27 1.27)
				)
			)
		)
		(duplicate_pad_numbers_are_jumpers no)
		(fp_line
			(start -0.7874 0.4064)
			(end -0.7874 -0.4064)
			(stroke
				(width 0.1524)
				(type default)
			)
			(layer "F.SilkS")
		)
		(fp_line
			(start 0.7874 0.4064)
			(end -0.7874 0.4064)
			(stroke
				(width 0.1524)
				(type default)
			)
			(layer "F.SilkS")
		)
		(fp_line
			(start -0.7874 -0.4064)
			(end 0.7874 -0.4064)
			(stroke
				(width 0.1524)
				(type default)
			)
			(layer "F.SilkS")
		)
		(fp_line
			(start 0.7874 -0.4064)
			(end 0.7874 0.4064)
			(stroke
				(width 0.1524)
				(type default)
			)
			(layer "F.SilkS")
		)
		(fp_line
			(start -0.67945 0.3048)
			(end -0.67945 -0.305054)
			(stroke
				(width 0.1)
				(type default)
			)
			(layer "F.Fab")
		)
		(fp_line
			(start -0.12065 0.3048)
			(end -0.67945 0.3048)
			(stroke
				(width 0.1)
				(type default)
			)
			(layer "F.Fab")
		)
		(fp_line
			(start 0.120396 0.3048)
			(end 0.120396 0.2794)
			(stroke
				(width 0.1)
				(type default)
			)
			(layer "F.Fab")
		)
		(fp_line
			(start 0.67945 0.3048)
			(end 0.120396 0.3048)
			(stroke
				(width 0.1)
				(type default)
			)
			(layer "F.Fab")
		)
		(fp_line
			(start -0.12065 0.2794)
			(end -0.12065 0.3048)
			(stroke
				(width 0.1)
				(type default)
			)
			(layer "F.Fab")
		)
		(fp_line
			(start 0.120396 0.2794)
			(end -0.12065 0.2794)
			(stroke
				(width 0.1)
				(type default)
			)
			(layer "F.Fab")
		)
		(fp_line
			(start -0.12065 -0.2794)
			(end 0.12065 -0.2794)
			(stroke
				(width 0.1)
				(type default)
			)
			(layer "F.Fab")
		)
		(fp_line
			(start 0.12065 -0.2794)
			(end 0.12065 -0.3048)
			(stroke
				(width 0.1)
				(type default)
			)
			(layer "F.Fab")
		)
		(fp_line
			(start 0.12065 -0.3048)
			(end 0.67945 -0.3048)
			(stroke
				(width 0.1)
				(type default)
			)
			(layer "F.Fab")
		)
		(fp_line
			(start 0.67945 -0.3048)
			(end 0.67945 0.3048)
			(stroke
				(width 0.1)
				(type default)
			)
			(layer "F.Fab")
		)
		(fp_line
			(start -0.67945 -0.305054)
			(end -0.12065 -0.305054)
			(stroke
				(width 0.1)
				(type default)
			)
			(layer "F.Fab")
		)
		(fp_line
			(start -0.12065 -0.305054)
			(end -0.12065 -0.2794)
			(stroke
				(width 0.1)
				(type default)
			)
			(layer "F.Fab")
		)
		(pad "1" smd circle
			(at -0.40005 0 270)
			(size 0 0)
			(layers "F.Cu" "F.Mask" "F.Paste")
			(net "P1V8_RETIMER_CPU0_VCC")
		)
		(pad "2" smd circle
			(at 0.40005 0 270)
			(size 0 0)
			(layers "F.Cu" "F.Mask" "F.Paste")
			(net "GND")
		)
	)
	(footprint ""
		(layer "F.Cu")
		(at 339.70722 -337.689698 90)
		(property "Reference" "PC131"
			(at 0 0 90)
			(layer "F.SilkS")
			(hide yes)
			(effects
				(font
					(size 1.27 1.27)
				)
			)
		)
		(property "Value" ""
			(at 0 0 90)
			(layer "F.Fab")
			(effects
				(font
					(size 1.27 1.27)
				)
			)
		)
		(duplicate_pad_numbers_are_jumpers no)
		(fp_line
			(start 0.7874 -0.4064)
			(end 0.7874 0.4064)
			(stroke
				(width 0.1524)
				(type default)
			)
			(layer "F.SilkS")
		)
		(fp_line
			(start -0.7874 -0.4064)
			(end 0.7874 -0.4064)
			(stroke
				(width 0.1524)
				(type default)
			)
			(layer "F.SilkS")
		)
		(fp_line
			(start 0.7874 0.4064)
			(end 0.435102 0.4064)
			(stroke
				(width 0.1524)
				(type default)
			)
			(layer "F.SilkS")
		)
		(fp_line
			(start -0.174498 0.4064)
			(end -0.7874 0.4064)
			(stroke
				(width 0.1524)
				(type default)
			)
			(layer "F.SilkS")
		)
		(fp_line
			(start -0.7874 0.4064)
			(end -0.7874 -0.4064)
			(stroke
				(width 0.1524)
				(type default)
			)
			(layer "F.SilkS")
		)
		(fp_line
			(start -0.12065 -0.305054)
			(end -0.12065 -0.2794)
			(stroke
				(width 0.1)
				(type default)
			)
			(layer "F.Fab")
		)
		(fp_line
			(start -0.67945 -0.305054)
			(end -0.12065 -0.305054)
			(stroke
				(width 0.1)
				(type default)
			)
			(layer "F.Fab")
		)
		(fp_line
			(start 0.67945 -0.3048)
			(end 0.67945 0.3048)
			(stroke
				(width 0.1)
				(type default)
			)
			(layer "F.Fab")
		)
		(fp_line
			(start 0.12065 -0.3048)
			(end 0.67945 -0.3048)
			(stroke
				(width 0.1)
				(type default)
			)
			(layer "F.Fab")
		)
		(fp_line
			(start 0.12065 -0.2794)
			(end 0.12065 -0.3048)
			(stroke
				(width 0.1)
				(type default)
			)
			(layer "F.Fab")
		)
		(fp_line
			(start -0.12065 -0.2794)
			(end 0.12065 -0.2794)
			(stroke
				(width 0.1)
				(type default)
			)
			(layer "F.Fab")
		)
		(fp_line
			(start 0.120396 0.2794)
			(end -0.12065 0.2794)
			(stroke
				(width 0.1)
				(type default)
			)
			(layer "F.Fab")
		)
		(fp_line
			(start -0.12065 0.2794)
			(end -0.12065 0.3048)
			(stroke
				(width 0.1)
				(type default)
			)
			(layer "F.Fab")
		)
		(fp_line
			(start 0.67945 0.3048)
			(end 0.120396 0.3048)
			(stroke
				(width 0.1)
				(type default)
			)
			(layer "F.Fab")
		)
		(fp_line
			(start 0.120396 0.3048)
			(end 0.120396 0.2794)
			(stroke
				(width 0.1)
				(type default)
			)
			(layer "F.Fab")
		)
		(fp_line
			(start -0.12065 0.3048)
			(end -0.67945 0.3048)
			(stroke
				(width 0.1)
				(type default)
			)
			(layer "F.Fab")
		)
		(fp_line
			(start -0.67945 0.3048)
			(end -0.67945 -0.305054)
			(stroke
				(width 0.1)
				(type default)
			)
			(layer "F.Fab")
		)
		(pad "1" smd circle
			(at -0.40005 0 90)
			(size 0 0)
			(layers "F.Cu" "F.Mask" "F.Paste")
			(net "PVDDCR_CPU1_P0_VCC5")
		)
		(pad "2" smd circle
			(at 0.40005 0 90)
			(size 0 0)
			(layers "F.Cu" "F.Mask" "F.Paste")
			(net "GND")
		)
	)
)
